(kicad_pcb
	(version 20260206)
	(generator "pcbnew")
	(generator_version "10.0")
	(general
		(thickness 1.6)
		(legacy_teardrops no)
	)
	(paper "A4")
	(title_block
		(title "Wiwynn_Tioga_Pass_MB.brd")
		(comment 1 "Tioga Pass / footprints 2255-2260 of 4770")
	)
	(layers
		(0 "F.Cu" signal "TOP")
		(4 "In1.Cu" signal "L2GND")
		(6 "In2.Cu" signal "L3")
		(8 "In3.Cu" signal "L4GND")
		(10 "In4.Cu" signal "L5")
		(12 "In5.Cu" signal "L6GND")
		(14 "In6.Cu" signal "L7VCC")
		(16 "In7.Cu" signal "L8VCC")
		(18 "In8.Cu" signal "L9GND")
		(20 "In9.Cu" signal "L10")
		(22 "In10.Cu" signal "L11GND")
		(24 "In11.Cu" signal "L12")
		(26 "In12.Cu" signal "L13GND")
		(2 "B.Cu" signal "BOTTOM")
		(9 "F.Adhes" user "F.Adhesive")
		(11 "B.Adhes" user "B.Adhesive")
		(13 "F.Paste" user "Package Geometry/Pastemask Top")
		(15 "B.Paste" user "Package Geometry/Pastemask Bottom")
		(5 "F.SilkS" user "Ref Des/Silkscreen Top")
		(7 "B.SilkS" user "Ref Des/Silkscreen Bottom")
		(1 "F.Mask" user "Board Geometry/Soldermask Top")
		(3 "B.Mask" user "Board Geometry/Soldermask Bottom")
		(17 "Dwgs.User" user "User.Drawings")
		(19 "Cmts.User" user "User.Comments")
		(21 "Eco1.User" user "User.Eco1")
		(23 "Eco2.User" user "User.Eco2")
		(25 "Edge.Cuts" user "Board Geometry/Outline")
		(27 "Margin" user)
		(31 "F.CrtYd" user "Package Geometry/Place Bound Top")
		(29 "B.CrtYd" user "Package Geometry/Place Bound Bottom")
		(35 "F.Fab" user "Ref Des/Assembly Top")
		(33 "B.Fab" user "Ref Des/Assembly Bottom")
	)
	(footprint ""
		(layer "F.Cu")
		(at -0.2794 -18.2118 90)
		(property "Reference" "RT21"
			(at 1.01473 0.656336 0)
			(unlocked yes)
			(layer "F.SilkS")
			(effects
				(font
					(size 0.4064 0.254)
					(thickness 0.1524)
				)
			)
		)
		(property "Value" ""
			(at 0 0 90)
			(layer "F.Fab")
			(effects
				(font
					(size 1.27 1.27)
				)
			)
		)
		(duplicate_pad_numbers_are_jumpers no)
		(fp_poly
			(pts
				(xy -0.4953 -0.2032) (xy 0.4953 -0.2032) (xy 0.4953 1.6002) (xy -0.4953 1.6002)
			)
			(stroke
				(width 0)
				(type default)
			)
			(fill no)
			(layer "F.CrtYd")
		)
		(fp_line
			(start 0.4953 -0.2032)
			(end 0.4953 1.6002)
			(stroke
				(width 0.1)
				(type default)
			)
			(layer "F.Fab")
		)
		(fp_line
			(start -0.4953 -0.2032)
			(end 0.4953 -0.2032)
			(stroke
				(width 0.1)
				(type default)
			)
			(layer "F.Fab")
		)
		(fp_line
			(start 0.4953 1.6002)
			(end -0.4953 1.6002)
			(stroke
				(width 0.1)
				(type default)
			)
			(layer "F.Fab")
		)
		(fp_line
			(start -0.4953 1.6002)
			(end -0.4953 -0.2032)
			(stroke
				(width 0.1)
				(type default)
			)
			(layer "F.Fab")
		)
		(pad "1" smd rect
			(at 0 0 90)
			(size 0.762 0.889)
			(layers "F.Cu" "F.Mask" "F.Paste")
			(net "VR_PVDDQ_GHJ_PH2_BOOT")
		)
		(pad "2" smd rect
			(at 0 1.397 90)
			(size 0.762 0.889)
			(layers "F.Cu" "F.Mask" "F.Paste")
			(net "VR_PVDDQ_GHJ_PH2_BOOT_R")
		)
		(zone
			(layer "F.Cu")
			(hatch none 0.5)
			(connect_pads
				(clearance 0)
			)
			(min_thickness 0.25)
			(keepout
				(tracks allowed)
				(vias not_allowed)
				(pads allowed)
				(copperpour not_allowed)
				(footprints allowed)
			)
			(placement
				(enabled no)
				(sheetname "")
			)
			(fill
				(thermal_gap 0.5)
				(thermal_bridge_width 0.5)
				(island_removal_mode 0)
			)
			(polygon
				(pts
					(xy 0.6731 -18.5928) (xy 0.1651 -18.5928) (xy 0.1651 -17.8308) (xy 0.6731 -17.8308)
				)
			)
		)
		(zone
			(layer "F.Cu")
			(hatch none 0.5)
			(connect_pads
				(clearance 0)
			)
			(min_thickness 0.25)
			(keepout
				(tracks not_allowed)
				(vias allowed)
				(pads allowed)
				(copperpour not_allowed)
				(footprints allowed)
			)
			(placement
				(enabled no)
				(sheetname "")
			)
			(fill
				(thermal_gap 0.5)
				(thermal_bridge_width 0.5)
				(island_removal_mode 0)
			)
			(polygon
				(pts
					(xy 0.6731 -17.8308) (xy 0.6731 -18.5928) (xy 0.1651 -18.5928) (xy 0.1651 -17.8308)
				)
			)
		)
	)
	(footprint ""
		(layer "F.Cu")
		(at 419.435026 -54.027832 90)
		(property "Reference" "R1W7"
			(at -0.8382 -0.67818 90)
			(unlocked yes)
			(layer "F.SilkS")
			(effects
				(font
					(size 0.4064 0.254)
					(thickness 0.1524)
				)
				(justify left)
			)
		)
		(property "Value" ""
			(at 0 0 90)
			(layer "F.Fab")
			(effects
				(font
					(size 1.27 1.27)
				)
			)
		)
		(duplicate_pad_numbers_are_jumpers no)
		(fp_poly
			(pts
				(xy -0.2794 -0.1016) (xy 0.2794 -0.1016) (xy 0.2794 0.9906) (xy -0.2794 0.9906)
			)
			(stroke
				(width 0)
				(type default)
			)
			(fill no)
			(layer "F.CrtYd")
		)
		(fp_line
			(start 0.2794 -0.1016)
			(end -0.2794 -0.1016)
			(stroke
				(width 0.1)
				(type default)
			)
			(layer "F.Fab")
		)
		(fp_line
			(start -0.2794 -0.1016)
			(end -0.2794 0.9906)
			(stroke
				(width 0.1)
				(type default)
			)
			(layer "F.Fab")
		)
		(fp_line
			(start 0.2794 0.9906)
			(end 0.2794 -0.1016)
			(stroke
				(width 0.1)
				(type default)
			)
			(layer "F.Fab")
		)
		(fp_line
			(start -0.2794 0.9906)
			(end 0.2794 0.9906)
			(stroke
				(width 0.1)
				(type default)
			)
			(layer "F.Fab")
		)
		(pad "1" smd rect
			(at 0 0 90)
			(size 0.508 0.508)
			(layers "F.Cu" "F.Mask" "F.Paste")
			(net "FM_OCP_MEZZC_PRES_LVT3_BMC")
		)
		(pad "2" smd rect
			(at 0 0.889 90)
			(size 0.508 0.508)
			(layers "F.Cu" "F.Mask" "F.Paste")
			(net "P3V3_STBY")
		)
		(zone
			(layer "F.Cu")
			(hatch none 0.5)
			(connect_pads
				(clearance 0)
			)
			(min_thickness 0.25)
			(keepout
				(tracks allowed)
				(vias not_allowed)
				(pads allowed)
				(copperpour not_allowed)
				(footprints allowed)
			)
			(placement
				(enabled no)
				(sheetname "")
			)
			(fill
				(thermal_gap 0.5)
				(thermal_bridge_width 0.5)
				(island_removal_mode 0)
			)
			(polygon
				(pts
					(xy 419.689026 -53.773832) (xy 419.689026 -54.281832) (xy 420.070026 -54.281832) (xy 420.070026 -53.773832)
				)
			)
		)
		(zone
			(layer "F.Cu")
			(hatch none 0.5)
			(connect_pads
				(clearance 0)
			)
			(min_thickness 0.25)
			(keepout
				(tracks not_allowed)
				(vias allowed)
				(pads allowed)
				(copperpour not_allowed)
				(footprints allowed)
			)
			(placement
				(enabled no)
				(sheetname "")
			)
			(fill
				(thermal_gap 0.5)
				(thermal_bridge_width 0.5)
				(island_removal_mode 0)
			)
			(polygon
				(pts
					(xy 420.070026 -53.773832) (xy 420.070026 -54.281832) (xy 419.689026 -54.281832) (xy 419.689026 -53.773832)
				)
			)
		)
	)
	(footprint ""
		(layer "F.Cu")
		(at 472.313 -29.845 90)
		(property "Reference" "R1W23"
			(at -0.8382 -0.67818 90)
			(unlocked yes)
			(layer "F.SilkS")
			(effects
				(font
					(size 0.4064 0.254)
					(thickness 0.1524)
				)
				(justify left)
			)
		)
		(property "Value" ""
			(at 0 0 90)
			(layer "F.Fab")
			(effects
				(font
					(size 1.27 1.27)
				)
			)
		)
		(duplicate_pad_numbers_are_jumpers no)
		(fp_poly
			(pts
				(xy -0.2794 -0.1016) (xy 0.2794 -0.1016) (xy 0.2794 0.9906) (xy -0.2794 0.9906)
			)
			(stroke
				(width 0)
				(type default)
			)
			(fill no)
			(layer "F.CrtYd")
		)
		(fp_line
			(start 0.2794 -0.1016)
			(end -0.2794 -0.1016)
			(stroke
				(width 0.1)
				(type default)
			)
			(layer "F.Fab")
		)
		(fp_line
			(start -0.2794 -0.1016)
			(end -0.2794 0.9906)
			(stroke
				(width 0.1)
				(type default)
			)
			(layer "F.Fab")
		)
		(fp_line
			(start 0.2794 0.9906)
			(end 0.2794 -0.1016)
			(stroke
				(width 0.1)
				(type default)
			)
			(layer "F.Fab")
		)
		(fp_line
			(start -0.2794 0.9906)
			(end 0.2794 0.9906)
			(stroke
				(width 0.1)
				(type default)
			)
			(layer "F.Fab")
		)
		(pad "1" smd rect
			(at 0 0 90)
			(size 0.508 0.508)
			(layers "F.Cu" "F.Mask" "F.Paste")
			(net "SMB_HOST_STBY_LVC3_SDA")
		)
		(pad "2" smd rect
			(at 0 0.889 90)
			(size 0.508 0.508)
			(layers "F.Cu" "F.Mask" "F.Paste")
			(net "SMB_HOST_STBY_LVC3_SDA_R4")
		)
		(zone
			(layer "F.Cu")
			(hatch none 0.5)
			(connect_pads
				(clearance 0)
			)
			(min_thickness 0.25)
			(keepout
				(tracks allowed)
				(vias not_allowed)
				(pads allowed)
				(copperpour not_allowed)
				(footprints allowed)
			)
			(placement
				(enabled no)
				(sheetname "")
			)
			(fill
				(thermal_gap 0.5)
				(thermal_bridge_width 0.5)
				(island_removal_mode 0)
			)
			(polygon
				(pts
					(xy 472.567 -29.591) (xy 472.567 -30.099) (xy 472.948 -30.099) (xy 472.948 -29.591)
				)
			)
		)
		(zone
			(layer "F.Cu")
			(hatch none 0.5)
			(connect_pads
				(clearance 0)
			)
			(min_thickness 0.25)
			(keepout
				(tracks not_allowed)
				(vias allowed)
				(pads allowed)
				(copperpour not_allowed)
				(footprints allowed)
			)
			(placement
				(enabled no)
				(sheetname "")
			)
			(fill
				(thermal_gap 0.5)
				(thermal_bridge_width 0.5)
				(island_removal_mode 0)
			)
			(polygon
				(pts
					(xy 472.948 -29.591) (xy 472.948 -30.099) (xy 472.567 -30.099) (xy 472.567 -29.591)
				)
			)
		)
	)
	(footprint ""
		(layer "F.Cu")
		(at 104.5591 -149.8092 90)
		(property "Reference" "C2A7"
			(at 1.848866 0.752348 90)
			(unlocked yes)
			(layer "F.SilkS")
			(effects
				(font
					(size 1.27 0.9652)
					(thickness 0.1524)
				)
			)
		)
		(property "Value" ""
			(at 0 0 90)
			(layer "F.Fab")
			(effects
				(font
					(size 1.27 1.27)
				)
			)
		)
		(duplicate_pad_numbers_are_jumpers no)
		(fp_rect
			(start -0.500126 1.598422)
			(end 0.500126 -0.201422)
			(stroke
				(width 0)
				(type default)
			)
			(fill no)
			(layer "F.CrtYd")
		)
		(fp_line
			(start 0.500126 -0.201422)
			(end 0.500126 1.598422)
			(stroke
				(width 0.1)
				(type default)
			)
			(layer "F.Fab")
		)
		(fp_line
			(start -0.500126 -0.201422)
			(end 0.500126 -0.201422)
			(stroke
				(width 0.1)
				(type default)
			)
			(layer "F.Fab")
		)
		(fp_line
			(start 0.500126 1.598422)
			(end -0.500126 1.598422)
			(stroke
				(width 0.1)
				(type default)
			)
			(layer "F.Fab")
		)
		(fp_line
			(start -0.500126 1.598422)
			(end -0.500126 -0.201422)
			(stroke
				(width 0.1)
				(type default)
			)
			(layer "F.Fab")
		)
		(pad "1" smd rect
			(at 0 0)
			(size 0.889 0.9906)
			(layers "F.Cu" "F.Mask" "F.Paste")
			(net "PVDDQ_KLM")
		)
		(pad "2" smd rect
			(at 0 1.397)
			(size 0.889 0.9906)
			(layers "F.Cu" "F.Mask" "F.Paste")
			(net "GND")
		)
		(zone
			(layer "F.Cu")
			(hatch none 0.5)
			(connect_pads
				(clearance 0)
			)
			(min_thickness 0.25)
			(keepout
				(tracks not_allowed)
				(vias allowed)
				(pads allowed)
				(copperpour not_allowed)
				(footprints allowed)
			)
			(placement
				(enabled no)
				(sheetname "")
			)
			(fill
				(thermal_gap 0.5)
				(thermal_bridge_width 0.5)
				(island_removal_mode 0)
			)
			(polygon
				(pts
					(xy 105.5116 -149.3139) (xy 105.5116 -150.3045) (xy 105.0036 -150.3045) (xy 105.0036 -149.3139)
				)
			)
		)
		(zone
			(layer "F.Cu")
			(hatch none 0.5)
			(connect_pads
				(clearance 0)
			)
			(min_thickness 0.25)
			(keepout
				(tracks allowed)
				(vias not_allowed)
				(pads allowed)
				(copperpour not_allowed)
				(footprints allowed)
			)
			(placement
				(enabled no)
				(sheetname "")
			)
			(fill
				(thermal_gap 0.5)
				(thermal_bridge_width 0.5)
				(island_removal_mode 0)
			)
			(polygon
				(pts
					(xy 105.5116 -149.3139) (xy 105.5116 -150.3045) (xy 105.0036 -150.3045) (xy 105.0036 -149.3139)
				)
			)
		)
	)
	(footprint ""
		(layer "F.Cu")
		(at 270.7132 -79.6036 180)
		(property "Reference" "C5D20"
			(at 0 0 180)
			(layer "F.SilkS")
			(hide yes)
			(effects
				(font
					(size 1.27 1.27)
				)
			)
		)
		(property "Value" ""
			(at 0 0 180)
			(layer "F.Fab")
			(effects
				(font
					(size 1.27 1.27)
				)
			)
		)
		(duplicate_pad_numbers_are_jumpers no)
		(fp_poly
			(pts
				(xy -0.4953 -0.2032) (xy 0.4953 -0.2032) (xy 0.4953 1.6002) (xy -0.4953 1.6002)
			)
			(stroke
				(width 0)
				(type default)
			)
			(fill no)
			(layer "F.CrtYd")
		)
		(fp_line
			(start 0.4953 1.6002)
			(end -0.4953 1.6002)
			(stroke
				(width 0.1)
				(type default)
			)
			(layer "F.Fab")
		)
		(fp_line
			(start 0.4953 -0.2032)
			(end 0.4953 1.6002)
			(stroke
				(width 0.1)
				(type default)
			)
			(layer "F.Fab")
		)
		(fp_line
			(start -0.4953 1.6002)
			(end -0.4953 -0.2032)
			(stroke
				(width 0.1)
				(type default)
			)
			(layer "F.Fab")
		)
		(fp_line
			(start -0.4953 -0.2032)
			(end 0.4953 -0.2032)
			(stroke
				(width 0.1)
				(type default)
			)
			(layer "F.Fab")
		)
		(pad "1" smd rect
			(at 0 0 180)
			(size 0.762 0.889)
			(layers "F.Cu" "F.Mask" "F.Paste")
			(net "PVCCMCP_CPU0")
		)
		(pad "2" smd rect
			(at 0 1.397 180)
			(size 0.762 0.889)
			(layers "F.Cu" "F.Mask" "F.Paste")
			(net "GND")
		)
		(zone
			(layer "F.Cu")
			(hatch none 0.5)
			(connect_pads
				(clearance 0)
			)
			(min_thickness 0.25)
			(keepout
				(tracks not_allowed)
				(vias allowed)
				(pads allowed)
				(copperpour not_allowed)
				(footprints allowed)
			)
			(placement
				(enabled no)
				(sheetname "")
			)
			(fill
				(thermal_gap 0.5)
				(thermal_bridge_width 0.5)
				(island_removal_mode 0)
			)
			(polygon
				(pts
					(xy 271.0942 -80.0481) (xy 270.3322 -80.0481) (xy 270.3322 -80.5561) (xy 271.0942 -80.5561)
				)
			)
		)
	)
	(footprint ""
		(layer "F.Cu")
		(at 376.879866 -17.869662 180)
		(property "Reference" "UN8F2"
			(at 3.446272 -4.713986 180)
			(unlocked yes)
			(layer "F.SilkS")
			(effects
				(font
					(size 1.27 0.964946)
					(thickness 0.000001)
				)
				(justify left)
			)
		)
		(property "Value" ""
			(at 0 0 180)
			(layer "F.Fab")
			(effects
				(font
					(size 1.27 1.27)
				)
			)
		)
		(duplicate_pad_numbers_are_jumpers no)
		(fp_line
			(start 11.645392 10.819892)
			(end -2.094738 10.819892)
			(stroke
				(width 0.1524)
				(type default)
			)
			(layer "F.SilkS")
		)
		(fp_line
			(start 11.645392 -1.929892)
			(end 11.645392 10.819892)
			(stroke
				(width 0.1524)
				(type default)
			)
			(layer "F.SilkS")
		)
		(fp_line
			(start -2.094738 10.819892)
			(end -2.094738 -1.929892)
			(stroke
				(width 0.1524)
				(type default)
			)
			(layer "F.SilkS")
		)
		(fp_line
			(start -2.094738 -1.929892)
			(end 11.645392 -1.929892)
			(stroke
				(width 0.1524)
				(type default)
			)
			(layer "F.SilkS")
		)
		(fp_circle
			(center -2.69621 -0.952754)
			(end -2.82321 -0.952754)
			(stroke
				(width 0.762)
				(type default)
			)
			(fill no)
			(layer "F.SilkS")
		)
		(fp_rect
			(start 15.404846 -3.284474)
			(end 11.645392 12.260326)
			(stroke
				(width 0)
				(type default)
			)
			(fill no)
			(layer "F.CrtYd")
		)
		(fp_rect
			(start 11.645392 -1.929892)
			(end -2.094738 10.819892)
			(stroke
				(width 0)
				(type default)
			)
			(fill no)
			(layer "F.CrtYd")
		)
		(fp_rect
			(start -2.094738 -3.284474)
			(end -5.600954 12.260326)
			(stroke
				(width 0)
				(type default)
			)
			(fill no)
			(layer "F.CrtYd")
		)
		(fp_poly
			(pts
				(xy 7.569962 10.819892) (xy 6.970014 12.21994) (xy 2.629916 12.21994) (xy 2.029968 10.819892)
			)
			(stroke
				(width 0)
				(type default)
			)
			(fill no)
			(layer "F.CrtYd")
		)
		(fp_poly
			(pts
				(xy 2.029968 -1.929892) (xy 2.629916 -3.32994) (xy 6.970014 -3.32994) (xy 7.569962 -1.929892)
			)
			(stroke
				(width 0)
				(type default)
			)
			(fill no)
			(layer "F.CrtYd")
		)
		(fp_line
			(start 11.645392 10.819892)
			(end -2.094738 10.819892)
			(stroke
				(width 0.1)
				(type default)
			)
			(layer "F.Fab")
		)
		(fp_line
			(start 11.645392 -1.929892)
			(end 11.645392 10.819892)
			(stroke
				(width 0.1)
				(type default)
			)
			(layer "F.Fab")
		)
		(fp_line
			(start 7.569962 10.819892)
			(end 6.970014 12.21994)
			(stroke
				(width 0.1)
				(type default)
			)
			(layer "F.Fab")
		)
		(fp_line
			(start 6.970014 12.21994)
			(end 2.629916 12.21994)
			(stroke
				(width 0.1)
				(type default)
			)
			(layer "F.Fab")
		)
		(fp_line
			(start 6.970014 -3.32994)
			(end 7.569962 -1.929892)
			(stroke
				(width 0.1)
				(type default)
			)
			(layer "F.Fab")
		)
		(fp_line
			(start 2.629916 12.21994)
			(end 2.029968 10.819892)
			(stroke
				(width 0.1)
				(type default)
			)
			(layer "F.Fab")
		)
		(fp_line
			(start 2.629916 -3.32994)
			(end 6.970014 -3.32994)
			(stroke
				(width 0.1)
				(type default)
			)
			(layer "F.Fab")
		)
		(fp_line
			(start 2.029968 -1.929892)
			(end 2.629916 -3.32994)
			(stroke
				(width 0.1)
				(type default)
			)
			(layer "F.Fab")
		)
		(fp_line
			(start -2.094738 10.819892)
			(end -2.094738 -1.929892)
			(stroke
				(width 0.1)
				(type default)
			)
			(layer "F.Fab")
		)
		(fp_line
			(start -2.094738 -1.929892)
			(end 11.645392 -1.929892)
			(stroke
				(width 0.1)
				(type default)
			)
			(layer "F.Fab")
		)
		(pad "1" smd rect
			(at 0 0 180)
			(size 1.9304 0.635)
			(layers "F.Cu" "F.Mask" "F.Paste")
			(net "PU_TPM_SPI_BMC_HOLD_N")
		)
		(pad "2" smd rect
			(at 0 1.27 180)
			(size 1.9304 0.635)
			(layers "F.Cu" "F.Mask" "F.Paste")
			(net "P3V3_STBY")
		)
		(pad "3" smd rect
			(at 0 2.54 180)
			(size 1.9304 0.635)
			(layers "F.Cu" "F.Mask" "F.Paste")
			(net "PU_TPM_SPI_FLASH_RESET_2_N")
		)
		(pad "4" smd rect
			(at 0 3.81 180)
			(size 1.9304 0.635)
			(layers "F.Cu" "F.Mask" "F.Paste")
			(net "TP_TPM_SPI_6")
		)
		(pad "5" smd rect
			(at 0 5.08 180)
			(size 1.9304 0.635)
			(layers "F.Cu" "F.Mask" "F.Paste")
			(net "TP_TPM_SPI_5")
		)
		(pad "6" smd rect
			(at 0 6.35 180)
			(size 1.9304 0.635)
			(layers "F.Cu" "F.Mask" "F.Paste")
			(net "TP_TPM_SPI_4")
		)
		(pad "7" smd rect
			(at 0 7.62 180)
			(size 1.9304 0.635)
			(layers "F.Cu" "F.Mask" "F.Paste")
			(net "SPI_BMC_BT_CS0_N")
		)
		(pad "8" smd rect
			(at 0 8.89 180)
			(size 1.9304 0.635)
			(layers "F.Cu" "F.Mask" "F.Paste")
			(net "SPI_TPM_BMC_DI_R")
		)
		(pad "9" smd rect
			(at 9.5504 8.89 180)
			(size 1.9304 0.635)
			(layers "F.Cu" "F.Mask" "F.Paste")
			(net "TPM_SPI_BMC_WP_N")
		)
		(pad "10" smd rect
			(at 9.5504 7.62 180)
			(size 1.9304 0.635)
			(layers "F.Cu" "F.Mask" "F.Paste")
			(net "GND")
		)
		(pad "11" smd rect
			(at 9.5504 6.35 180)
			(size 1.9304 0.635)
			(layers "F.Cu" "F.Mask" "F.Paste")
			(net "TP_TPM_SPI_3")
		)
		(pad "12" smd rect
			(at 9.5504 5.08 180)
			(size 1.9304 0.635)
			(layers "F.Cu" "F.Mask" "F.Paste")
			(net "TP_TPM_SPI_2")
		)
		(pad "13" smd rect
			(at 9.5504 3.81 180)
			(size 1.9304 0.635)
			(layers "F.Cu" "F.Mask" "F.Paste")
			(net "TP_TPM_SPI_1")
		)
		(pad "14" smd rect
			(at 9.5504 2.54 180)
			(size 1.9304 0.635)
			(layers "F.Cu" "F.Mask" "F.Paste")
			(net "TP_TPM_SPI_0")
		)
		(pad "15" smd rect
			(at 9.5504 1.27 180)
			(size 1.9304 0.635)
			(layers "F.Cu" "F.Mask" "F.Paste")
			(net "SPI_BMC_BT_DO")
		)
		(pad "16" smd rect
			(at 9.5504 0 180)
			(size 1.9304 0.635)
			(layers "F.Cu" "F.Mask" "F.Paste")
			(net "SPI_BMC_BT_CLK")
		)
	)
)
